(kicad_pcb
	(version 20221018)
	(generator pcbnew)
	(general
    (thickness 1.586)
  )
	(paper "A4")
	(title_block
    (date "2024-03-26")
    (rev "1.1.3")
		(comment 9 "footprint 10 of 146 (J7), pads 1-100 of 100")
	)
	(layers
    (0 "F.Cu" signal)
    (1 "In1.Cu" power)
    (2 "In2.Cu" power)
    (31 "B.Cu" signal)
    (32 "B.Adhes" user "B.Adhesive")
    (33 "F.Adhes" user "F.Adhesive")
    (34 "B.Paste" user)
    (35 "F.Paste" user)
    (36 "B.SilkS" user "B.Silkscreen")
    (37 "F.SilkS" user "F.Silkscreen")
    (38 "B.Mask" user)
    (39 "F.Mask" user)
    (40 "Dwgs.User" user "User.Drawings")
    (41 "Cmts.User" user "User.Comments")
    (42 "Eco1.User" user "User.Eco1")
    (43 "Eco2.User" user "User.Eco2")
    (44 "Edge.Cuts" user)
    (45 "Margin" user)
    (46 "B.CrtYd" user "B.Courtyard")
    (47 "F.CrtYd" user "F.Courtyard")
    (48 "B.Fab" user)
    (49 "F.Fab" user)
  )
	(footprint "scalenode-cm4-baseboard-footprints:Conn_Socket_Hirose_DF40_2x50_DF40HC-3.0-100DS-0.4V"
    (layer "F.Cu")
    (at 167.17772 59.80168 180)
    (property "Author" "Antmicro")
    (property "License" "Apache-2.0")
    (property "MPN" "DF40HC(3.0)-100DS-0.4V(51)")
    (property "Manufacturer" "Hirose Electric")
    (property "Pitch" "0.4 mm")
    (property "Sheetfile" "compute-module.kicad_sch")
    (property "Sheetname" "Compute module")
    (property "ki_description" "100 Position Connector Receptacle, Center Strip Contacts Surface Mount Gold")
    (property "ki_keywords" "CONNECTOR, B2B, SOCKET")
    (attr smd)
    (fp_text reference "J7" (at -12.87 0.119) (layer "F.SilkS")
        (effects (font (size 0.7 0.7) (thickness 0.15)) (justify left bottom))
    )
    (fp_text value "Socket_Hirose_DF40_2x50_DF40HC-3.0-100DS-0.4V" (at 0.57772 0.90168) (layer "F.Fab")
        (effects (font (size 0.7 0.7) (thickness 0.15)) (justify left bottom))
    )
    (pad "1" smd rect (at -9.801 1.54 180) (size 0.2 0.7) (layers "F.Cu" "F.Paste" "F.Mask")
      (net 11 "GND") (pintype "passive"))
    (pad "2" smd rect (at -9.801 -1.541 180) (size 0.2 0.7) (layers "F.Cu" "F.Paste" "F.Mask")
      (net 11 "GND") (pintype "passive"))
    (pad "3" smd rect (at -9.401 1.54 180) (size 0.2 0.7) (layers "F.Cu" "F.Paste" "F.Mask")
      (net 94 "TRD3_P") (pintype "passive"))
    (pad "4" smd rect (at -9.401 -1.541 180) (size 0.2 0.7) (layers "F.Cu" "F.Paste" "F.Mask")
      (net 93 "TRD1_P") (pintype "passive"))
    (pad "5" smd rect (at -9 1.54 180) (size 0.2 0.7) (layers "F.Cu" "F.Paste" "F.Mask")
      (net 92 "TRD3_N") (pintype "passive"))
    (pad "6" smd rect (at -9 -1.541 180) (size 0.2 0.7) (layers "F.Cu" "F.Paste" "F.Mask")
      (net 91 "TRD1_N") (pintype "passive"))
    (pad "7" smd rect (at -8.6 1.54 180) (size 0.2 0.7) (layers "F.Cu" "F.Paste" "F.Mask")
      (net 11 "GND") (pintype "passive"))
    (pad "8" smd rect (at -8.6 -1.541 180) (size 0.2 0.7) (layers "F.Cu" "F.Paste" "F.Mask")
      (net 11 "GND") (pintype "passive"))
    (pad "9" smd rect (at -8.2 1.54 180) (size 0.2 0.7) (layers "F.Cu" "F.Paste" "F.Mask")
      (net 90 "TRD2_N") (pintype "passive"))
    (pad "10" smd rect (at -8.2 -1.541 180) (size 0.2 0.7) (layers "F.Cu" "F.Paste" "F.Mask")
      (net 89 "TRD0_N") (pintype "passive"))
    (pad "11" smd rect (at -7.8 1.54 180) (size 0.2 0.7) (layers "F.Cu" "F.Paste" "F.Mask")
      (net 88 "TRD2_P") (pintype "passive"))
    (pad "12" smd rect (at -7.8 -1.541 180) (size 0.2 0.7) (layers "F.Cu" "F.Paste" "F.Mask")
      (net 87 "TRD0_P") (pintype "passive"))
    (pad "13" smd rect (at -7.401 1.54 180) (size 0.2 0.7) (layers "F.Cu" "F.Paste" "F.Mask")
      (net 11 "GND") (pintype "passive"))
    (pad "14" smd rect (at -7.401 -1.541 180) (size 0.2 0.7) (layers "F.Cu" "F.Paste" "F.Mask")
      (net 11 "GND") (pintype "passive"))
    (pad "15" smd rect (at -7 1.54 180) (size 0.2 0.7) (layers "F.Cu" "F.Paste" "F.Mask")
      (net 84 "ETH_LEDG") (pintype "passive"))
    (pad "16" smd rect (at -7 -1.541 180) (size 0.2 0.7) (layers "F.Cu" "F.Paste" "F.Mask")
      (net 85 "SYNC_IN") (pintype "passive"))
    (pad "17" smd rect (at -6.6 1.54 180) (size 0.2 0.7) (layers "F.Cu" "F.Paste" "F.Mask")
      (net 86 "ETH_LEDY") (pintype "passive"))
    (pad "18" smd rect (at -6.6 -1.541 180) (size 0.2 0.7) (layers "F.Cu" "F.Paste" "F.Mask")
      (net 83 "SYNC_OUT") (pintype "passive"))
    (pad "19" smd rect (at -6.201 1.54 180) (size 0.2 0.7) (layers "F.Cu" "F.Paste" "F.Mask")
      (net 203 "unconnected-(J7-Pad19)") (pintype "passive+no_connect"))
    (pad "20" smd rect (at -6.201 -1.541 180) (size 0.2 0.7) (layers "F.Cu" "F.Paste" "F.Mask")
      (net 82 "EEPROM_nWP") (pintype "passive"))
    (pad "21" smd rect (at -5.8 1.54 180) (size 0.2 0.7) (layers "F.Cu" "F.Paste" "F.Mask")
      (net 227 "Net-(J7-Pad21)") (pintype "passive"))
    (pad "22" smd rect (at -5.8 -1.541 180) (size 0.2 0.7) (layers "F.Cu" "F.Paste" "F.Mask")
      (net 11 "GND") (pintype "passive"))
    (pad "23" smd rect (at -5.401 1.54 180) (size 0.2 0.7) (layers "F.Cu" "F.Paste" "F.Mask")
      (net 11 "GND") (pintype "passive"))
    (pad "24" smd rect (at -5.401 -1.541 180) (size 0.2 0.7) (layers "F.Cu" "F.Paste" "F.Mask")
      (net 80 "GPIO26") (pintype "passive"))
    (pad "25" smd rect (at -5 1.54 180) (size 0.2 0.7) (layers "F.Cu" "F.Paste" "F.Mask")
      (net 81 "GPIO21") (pintype "passive"))
    (pad "26" smd rect (at -5 -1.541 180) (size 0.2 0.7) (layers "F.Cu" "F.Paste" "F.Mask")
      (net 78 "GPIO19") (pintype "passive"))
    (pad "27" smd rect (at -4.6 1.54 180) (size 0.2 0.7) (layers "F.Cu" "F.Paste" "F.Mask")
      (net 79 "GPIO20") (pintype "passive"))
    (pad "28" smd rect (at -4.6 -1.541 180) (size 0.2 0.7) (layers "F.Cu" "F.Paste" "F.Mask")
      (net 76 "GPIO13") (pintype "passive"))
    (pad "29" smd rect (at -4.201 1.54 180) (size 0.2 0.7) (layers "F.Cu" "F.Paste" "F.Mask")
      (net 77 "GPIO16") (pintype "passive"))
    (pad "30" smd rect (at -4.201 -1.541 180) (size 0.2 0.7) (layers "F.Cu" "F.Paste" "F.Mask")
      (net 74 "GPIO6") (pintype "passive"))
    (pad "31" smd rect (at -3.8 1.54 180) (size 0.2 0.7) (layers "F.Cu" "F.Paste" "F.Mask")
      (net 75 "GPIO12") (pintype "passive"))
    (pad "32" smd rect (at -3.8 -1.541 180) (size 0.2 0.7) (layers "F.Cu" "F.Paste" "F.Mask")
      (net 11 "GND") (pintype "passive"))
    (pad "33" smd rect (at -3.4 1.54 180) (size 0.2 0.7) (layers "F.Cu" "F.Paste" "F.Mask")
      (net 11 "GND") (pintype "passive"))
    (pad "34" smd rect (at -3.4 -1.541 180) (size 0.2 0.7) (layers "F.Cu" "F.Paste" "F.Mask")
      (net 72 "GPIO5") (pintype "passive"))
    (pad "35" smd rect (at -3 1.54 180) (size 0.2 0.7) (layers "F.Cu" "F.Paste" "F.Mask")
      (net 73 "ID_SC") (pintype "passive"))
    (pad "36" smd rect (at -3 -1.541 180) (size 0.2 0.7) (layers "F.Cu" "F.Paste" "F.Mask")
      (net 70 "ID_SD") (pintype "passive"))
    (pad "37" smd rect (at -2.601 1.54 180) (size 0.2 0.7) (layers "F.Cu" "F.Paste" "F.Mask")
      (net 71 "GPIO7") (pintype "passive"))
    (pad "38" smd rect (at -2.601 -1.541 180) (size 0.2 0.7) (layers "F.Cu" "F.Paste" "F.Mask")
      (net 68 "GPIO11") (pintype "passive"))
    (pad "39" smd rect (at -2.201 1.54 180) (size 0.2 0.7) (layers "F.Cu" "F.Paste" "F.Mask")
      (net 69 "GPIO8") (pintype "passive"))
    (pad "40" smd rect (at -2.201 -1.541 180) (size 0.2 0.7) (layers "F.Cu" "F.Paste" "F.Mask")
      (net 66 "GPIO9") (pintype "passive"))
    (pad "41" smd rect (at -1.801 1.54 180) (size 0.2 0.7) (layers "F.Cu" "F.Paste" "F.Mask")
      (net 67 "GPIO25") (pintype "passive"))
    (pad "42" smd rect (at -1.801 -1.541 180) (size 0.2 0.7) (layers "F.Cu" "F.Paste" "F.Mask")
      (net 11 "GND") (pintype "passive"))
    (pad "43" smd rect (at -1.4 1.54 180) (size 0.2 0.7) (layers "F.Cu" "F.Paste" "F.Mask")
      (net 11 "GND") (pintype "passive"))
    (pad "44" smd rect (at -1.4 -1.541 180) (size 0.2 0.7) (layers "F.Cu" "F.Paste" "F.Mask")
      (net 64 "GPIO10") (pintype "passive"))
    (pad "45" smd rect (at -1 1.54 180) (size 0.2 0.7) (layers "F.Cu" "F.Paste" "F.Mask")
      (net 65 "GPIO24") (pintype "passive"))
    (pad "46" smd rect (at -1 -1.541 180) (size 0.2 0.7) (layers "F.Cu" "F.Paste" "F.Mask")
      (net 62 "GPIO22") (pintype "passive"))
    (pad "47" smd rect (at -0.6 1.54 180) (size 0.2 0.7) (layers "F.Cu" "F.Paste" "F.Mask")
      (net 63 "GPIO23") (pintype "passive"))
    (pad "48" smd rect (at -0.6 -1.541 180) (size 0.2 0.7) (layers "F.Cu" "F.Paste" "F.Mask")
      (net 60 "GPIO27") (pintype "passive"))
    (pad "49" smd rect (at -0.201 1.54 180) (size 0.2 0.7) (layers "F.Cu" "F.Paste" "F.Mask")
      (net 61 "GPIO18") (pintype "passive"))
    (pad "50" smd rect (at -0.201 -1.541 180) (size 0.2 0.7) (layers "F.Cu" "F.Paste" "F.Mask")
      (net 59 "GPIO17") (pintype "passive"))
    (pad "51" smd rect (at 0.2 1.54 180) (size 0.2 0.7) (layers "F.Cu" "F.Paste" "F.Mask")
      (net 241 "RPi_RXD") (pintype "passive"))
    (pad "52" smd rect (at 0.2 -1.541 180) (size 0.2 0.7) (layers "F.Cu" "F.Paste" "F.Mask")
      (net 11 "GND") (pintype "passive"))
    (pad "53" smd rect (at 0.599 1.54 180) (size 0.2 0.7) (layers "F.Cu" "F.Paste" "F.Mask")
      (net 11 "GND") (pintype "passive"))
    (pad "54" smd rect (at 0.599 -1.541 180) (size 0.2 0.7) (layers "F.Cu" "F.Paste" "F.Mask")
      (net 58 "GPIO4") (pintype "passive"))
    (pad "55" smd rect (at 0.999 1.54 180) (size 0.2 0.7) (layers "F.Cu" "F.Paste" "F.Mask")
      (net 242 "RPi_TXD") (pintype "passive"))
    (pad "56" smd rect (at 0.999 -1.541 180) (size 0.2 0.7) (layers "F.Cu" "F.Paste" "F.Mask")
      (net 57 "GPIO3") (pintype "passive"))
    (pad "57" smd rect (at 1.399 1.54 180) (size 0.2 0.7) (layers "F.Cu" "F.Paste" "F.Mask")
      (net 30 "SD_CLK") (pintype "passive"))
    (pad "58" smd rect (at 1.399 -1.541 180) (size 0.2 0.7) (layers "F.Cu" "F.Paste" "F.Mask")
      (net 56 "GPIO2") (pintype "passive"))
    (pad "59" smd rect (at 1.8 1.54 180) (size 0.2 0.7) (layers "F.Cu" "F.Paste" "F.Mask")
      (net 11 "GND") (pintype "passive"))
    (pad "60" smd rect (at 1.8 -1.541 180) (size 0.2 0.7) (layers "F.Cu" "F.Paste" "F.Mask")
      (net 11 "GND") (pintype "passive"))
    (pad "61" smd rect (at 2.2 1.54 180) (size 0.2 0.7) (layers "F.Cu" "F.Paste" "F.Mask")
      (net 32 "SD_DAT3") (pintype "passive"))
    (pad "62" smd rect (at 2.2 -1.541 180) (size 0.2 0.7) (layers "F.Cu" "F.Paste" "F.Mask")
      (net 31 "SD_CMD") (pintype "passive"))
    (pad "63" smd rect (at 2.6 1.54 180) (size 0.2 0.7) (layers "F.Cu" "F.Paste" "F.Mask")
      (net 29 "SD_DAT0") (pintype "passive"))
    (pad "64" smd rect (at 2.6 -1.541 180) (size 0.2 0.7) (layers "F.Cu" "F.Paste" "F.Mask")
      (net 204 "unconnected-(J7-Pad64)") (pintype "passive+no_connect"))
    (pad "65" smd rect (at 2.999 1.54 180) (size 0.2 0.7) (layers "F.Cu" "F.Paste" "F.Mask")
      (net 11 "GND") (pintype "passive"))
    (pad "66" smd rect (at 2.999 -1.541 180) (size 0.2 0.7) (layers "F.Cu" "F.Paste" "F.Mask")
      (net 11 "GND") (pintype "passive"))
    (pad "67" smd rect (at 3.399 1.54 180) (size 0.2 0.7) (layers "F.Cu" "F.Paste" "F.Mask")
      (net 28 "SD_DAT1") (pintype "passive"))
    (pad "68" smd rect (at 3.399 -1.541 180) (size 0.2 0.7) (layers "F.Cu" "F.Paste" "F.Mask")
      (net 205 "unconnected-(J7-Pad68)") (pintype "passive+no_connect"))
    (pad "69" smd rect (at 3.799 1.54 180) (size 0.2 0.7) (layers "F.Cu" "F.Paste" "F.Mask")
      (net 33 "SD_DAT2") (pintype "passive"))
    (pad "70" smd rect (at 3.799 -1.541 180) (size 0.2 0.7) (layers "F.Cu" "F.Paste" "F.Mask")
      (net 206 "unconnected-(J7-Pad70)") (pintype "passive+no_connect"))
    (pad "71" smd rect (at 4.2 1.54 180) (size 0.2 0.7) (layers "F.Cu" "F.Paste" "F.Mask")
      (net 11 "GND") (pintype "passive"))
    (pad "72" smd rect (at 4.2 -1.541 180) (size 0.2 0.7) (layers "F.Cu" "F.Paste" "F.Mask")
      (net 207 "unconnected-(J7-Pad72)") (pintype "passive+no_connect"))
    (pad "73" smd rect (at 4.599 1.54 180) (size 0.2 0.7) (layers "F.Cu" "F.Paste" "F.Mask")
      (net 208 "unconnected-(J7-Pad73)") (pintype "passive+no_connect"))
    (pad "74" smd rect (at 4.599 -1.541 180) (size 0.2 0.7) (layers "F.Cu" "F.Paste" "F.Mask")
      (net 11 "GND") (pintype "passive"))
    (pad "75" smd rect (at 4.999 1.54 180) (size 0.2 0.7) (layers "F.Cu" "F.Paste" "F.Mask")
      (net 55 "SD_PWR_ON") (pintype "passive"))
    (pad "76" smd rect (at 4.999 -1.541 180) (size 0.2 0.7) (layers "F.Cu" "F.Paste" "F.Mask")
      (net 54 "RESERVED") (pintype "passive"))
    (pad "77" smd rect (at 5.4 1.54 180) (size 0.2 0.7) (layers "F.Cu" "F.Paste" "F.Mask")
      (net 12 "VCC5V0") (pintype "passive"))
    (pad "78" smd rect (at 5.4 -1.541 180) (size 0.2 0.7) (layers "F.Cu" "F.Paste" "F.Mask")
      (net 232 "3V3_RPi") (pintype "passive"))
    (pad "79" smd rect (at 5.799 1.54 180) (size 0.2 0.7) (layers "F.Cu" "F.Paste" "F.Mask")
      (net 12 "VCC5V0") (pintype "passive"))
    (pad "80" smd rect (at 5.799 -1.541 180) (size 0.2 0.7) (layers "F.Cu" "F.Paste" "F.Mask")
      (net 53 "SCL0") (pintype "passive"))
    (pad "81" smd rect (at 6.2 1.54 180) (size 0.2 0.7) (layers "F.Cu" "F.Paste" "F.Mask")
      (net 12 "VCC5V0") (pintype "passive"))
    (pad "82" smd rect (at 6.2 -1.541 180) (size 0.2 0.7) (layers "F.Cu" "F.Paste" "F.Mask")
      (net 52 "SDA0") (pintype "passive"))
    (pad "83" smd rect (at 6.599 1.54 180) (size 0.2 0.7) (layers "F.Cu" "F.Paste" "F.Mask")
      (net 12 "VCC5V0") (pintype "passive"))
    (pad "84" smd rect (at 6.599 -1.541 180) (size 0.2 0.7) (layers "F.Cu" "F.Paste" "F.Mask")
      (net 232 "3V3_RPi") (pintype "passive"))
    (pad "85" smd rect (at 6.999 1.54 180) (size 0.2 0.7) (layers "F.Cu" "F.Paste" "F.Mask")
      (net 12 "VCC5V0") (pintype "passive"))
    (pad "86" smd rect (at 6.999 -1.541 180) (size 0.2 0.7) (layers "F.Cu" "F.Paste" "F.Mask")
      (net 232 "3V3_RPi") (pintype "passive"))
    (pad "87" smd rect (at 7.4 1.54 180) (size 0.2 0.7) (layers "F.Cu" "F.Paste" "F.Mask")
      (net 12 "VCC5V0") (pintype "passive"))
    (pad "88" smd rect (at 7.4 -1.541 180) (size 0.2 0.7) (layers "F.Cu" "F.Paste" "F.Mask")
      (net 50 "VCC1V8") (pintype "passive"))
    (pad "89" smd rect (at 7.799 1.54 180) (size 0.2 0.7) (layers "F.Cu" "F.Paste" "F.Mask")
      (net 51 "WL_nDis") (pintype "passive"))
    (pad "90" smd rect (at 7.799 -1.541 180) (size 0.2 0.7) (layers "F.Cu" "F.Paste" "F.Mask")
      (net 50 "VCC1V8") (pintype "passive"))
    (pad "91" smd rect (at 8.199 1.54 180) (size 0.2 0.7) (layers "F.Cu" "F.Paste" "F.Mask")
      (net 49 "BT_nDis") (pintype "passive"))
    (pad "92" smd rect (at 8.199 -1.541 180) (size 0.2 0.7) (layers "F.Cu" "F.Paste" "F.Mask")
      (net 48 "RUN_PG") (pintype "passive"))
    (pad "93" smd rect (at 8.599 1.54 180) (size 0.2 0.7) (layers "F.Cu" "F.Paste" "F.Mask")
      (net 243 "/Compute module/nRPi_BOOT") (pintype "passive"))
    (pad "94" smd rect (at 8.599 -1.541 180) (size 0.2 0.7) (layers "F.Cu" "F.Paste" "F.Mask")
      (net 47 "AIN1") (pintype "passive"))
    (pad "95" smd rect (at 8.999 1.54 180) (size 0.2 0.7) (layers "F.Cu" "F.Paste" "F.Mask")
      (net 46 "nPWR_LED") (pintype "passive"))
    (pad "96" smd rect (at 8.999 -1.541 180) (size 0.2 0.7) (layers "F.Cu" "F.Paste" "F.Mask")
      (net 45 "AIN0") (pintype "passive"))
    (pad "97" smd rect (at 9.4 1.54 180) (size 0.2 0.7) (layers "F.Cu" "F.Paste" "F.Mask")
      (net 44 "CAM_GPIO") (pintype "passive"))
    (pad "98" smd rect (at 9.4 -1.541 180) (size 0.2 0.7) (layers "F.Cu" "F.Paste" "F.Mask")
      (net 11 "GND") (pintype "passive"))
    (pad "99" smd rect (at 9.8 1.54 180) (size 0.2 0.7) (layers "F.Cu" "F.Paste" "F.Mask")
      (net 43 "GLOBAL_EN") (pintype "passive"))
    (pad "100" smd rect (at 9.8 -1.541 180) (size 0.2 0.7) (layers "F.Cu" "F.Paste" "F.Mask")
      (net 42 "nEXTRST") (pintype "passive"))
  )
)
